# T6G (Grand Teton) — schematic netlist excerpt (pin names and nets, part order shuffled) for the footprints in the layout excerpt that follows; sources: Cadence DE-HDL packaged netlist, KiCad conversion of 04192023_DAF0TMB3IC0_F0TG_MB_C_brd_V02_OCP.brd

PC2214  Q_CAP  0.01UF 50V 10% EMPTY  pkg C0402  page 146 : A = P12V_E1S_0 ; B = P12V_E1S_GATE_0
R581  Q_RES  4.7K 5% EMPTY  pkg 0402LF  page 28 : A = RST_CPU0_RSMRST_N ; B = PVDD18_S5_P0
R634  Q_RES  51.1 1% EMPTY  pkg 0201LF  page 298 : A = CLK_100M_RETIMER_CPU0_P2_DP ; B = GND

(kicad_pcb
	(version 20260206)
	(generator "pcbnew")
	(generator_version "10.0")
	(general
		(thickness 1.6)
		(legacy_teardrops no)
	)
	(paper "A4")
	(title_block
		(title "04192023_DAF0TMB3IC0_F0TG_MB_C_brd_V02_OCP.brd")
		(comment 1 "Grand Teton / footprints 2653-2655 of 8354")
	)
	(layers
		(0 "F.Cu" signal "TOP")
		(4 "In1.Cu" signal "GND")
		(6 "In2.Cu" signal "IN1")
		(8 "In3.Cu" signal "GND1")
		(10 "In4.Cu" signal "IN2")
		(12 "In5.Cu" signal "GND2")
		(14 "In6.Cu" signal "IN3")
		(16 "In7.Cu" signal "GND3")
		(18 "In8.Cu" signal "VCC")
		(20 "In9.Cu" signal "VCC1")
		(22 "In10.Cu" signal "GND4")
		(24 "In11.Cu" signal "IN4")
		(26 "In12.Cu" signal "GND5")
		(28 "In13.Cu" signal "IN5")
		(30 "In14.Cu" signal "GND6")
		(32 "In15.Cu" signal "IN6")
		(34 "In16.Cu" signal "GND7")
		(2 "B.Cu" signal "BOTTOM")
		(9 "F.Adhes" user "F.Adhesive")
		(11 "B.Adhes" user "B.Adhesive")
		(13 "F.Paste" user "Package Geometry/Pastemask Top")
		(15 "B.Paste" user "Package Geometry/Pastemask Bottom")
		(5 "F.SilkS" user "Ref Des/Silkscreen Top")
		(7 "B.SilkS" user "Ref Des/Silkscreen Bottom")
		(1 "F.Mask" user "Board Geometry/Soldermask Top")
		(3 "B.Mask" user "Board Geometry/Soldermask Bottom")
		(17 "Dwgs.User" user "User.Drawings")
		(19 "Cmts.User" user "User.Comments")
		(21 "Eco1.User" user "User.Eco1")
		(23 "Eco2.User" user "User.Eco2")
		(25 "Edge.Cuts" user "Board Geometry/Outline")
		(27 "Margin" user)
		(31 "F.CrtYd" user "Package Geometry/Place Bound Top")
		(29 "B.CrtYd" user "Package Geometry/Place Bound Bottom")
		(35 "F.Fab" user "Ref Des/Assembly Top")
		(33 "B.Fab" user "Ref Des/Assembly Bottom")
	)
	(footprint ""
		(layer "F.Cu")
		(at 256.47269 -40.498522 90)
		(property "Reference" "PC2214"
			(at 0 0 90)
			(layer "F.SilkS")
			(hide yes)
			(effects
				(font
					(size 1.27 1.27)
				)
			)
		)
		(property "Value" ""
			(at 0 0 90)
			(layer "F.Fab")
			(effects
				(font
					(size 1.27 1.27)
				)
			)
		)
		(duplicate_pad_numbers_are_jumpers no)
		(fp_line
			(start 0.7874 -0.4064)
			(end 0.7874 0.4064)
			(stroke
				(width 0.1524)
				(type default)
			)
			(layer "F.SilkS")
		)
		(fp_line
			(start -0.7874 -0.4064)
			(end 0.7874 -0.4064)
			(stroke
				(width 0.1524)
				(type default)
			)
			(layer "F.SilkS")
		)
		(fp_line
			(start 0.7874 0.4064)
			(end -0.7874 0.4064)
			(stroke
				(width 0.1524)
				(type default)
			)
			(layer "F.SilkS")
		)
		(fp_line
			(start -0.7874 0.4064)
			(end -0.7874 -0.4064)
			(stroke
				(width 0.1524)
				(type default)
			)
			(layer "F.SilkS")
		)
		(fp_line
			(start -0.12065 -0.305054)
			(end -0.12065 -0.2794)
			(stroke
				(width 0.1)
				(type default)
			)
			(layer "F.Fab")
		)
		(fp_line
			(start -0.67945 -0.305054)
			(end -0.12065 -0.305054)
			(stroke
				(width 0.1)
				(type default)
			)
			(layer "F.Fab")
		)
		(fp_line
			(start 0.67945 -0.3048)
			(end 0.67945 0.3048)
			(stroke
				(width 0.1)
				(type default)
			)
			(layer "F.Fab")
		)
		(fp_line
			(start 0.12065 -0.3048)
			(end 0.67945 -0.3048)
			(stroke
				(width 0.1)
				(type default)
			)
			(layer "F.Fab")
		)
		(fp_line
			(start 0.12065 -0.2794)
			(end 0.12065 -0.3048)
			(stroke
				(width 0.1)
				(type default)
			)
			(layer "F.Fab")
		)
		(fp_line
			(start -0.12065 -0.2794)
			(end 0.12065 -0.2794)
			(stroke
				(width 0.1)
				(type default)
			)
			(layer "F.Fab")
		)
		(fp_line
			(start 0.120396 0.2794)
			(end -0.12065 0.2794)
			(stroke
				(width 0.1)
				(type default)
			)
			(layer "F.Fab")
		)
		(fp_line
			(start -0.12065 0.2794)
			(end -0.12065 0.3048)
			(stroke
				(width 0.1)
				(type default)
			)
			(layer "F.Fab")
		)
		(fp_line
			(start 0.67945 0.3048)
			(end 0.120396 0.3048)
			(stroke
				(width 0.1)
				(type default)
			)
			(layer "F.Fab")
		)
		(fp_line
			(start 0.120396 0.3048)
			(end 0.120396 0.2794)
			(stroke
				(width 0.1)
				(type default)
			)
			(layer "F.Fab")
		)
		(fp_line
			(start -0.12065 0.3048)
			(end -0.67945 0.3048)
			(stroke
				(width 0.1)
				(type default)
			)
			(layer "F.Fab")
		)
		(fp_line
			(start -0.67945 0.3048)
			(end -0.67945 -0.305054)
			(stroke
				(width 0.1)
				(type default)
			)
			(layer "F.Fab")
		)
		(pad "1" smd circle
			(at -0.40005 0 90)
			(size 0 0)
			(layers "F.Cu" "F.Mask" "F.Paste")
			(net "P12V_E1S_0")
		)
		(pad "2" smd circle
			(at 0.40005 0 90)
			(size 0 0)
			(layers "F.Cu" "F.Mask" "F.Paste")
			(net "P12V_E1S_GATE_0")
		)
	)
	(footprint ""
		(layer "F.Cu")
		(at 399.171668 -396.412974 90)
		(property "Reference" "R634"
			(at 0 0 90)
			(layer "F.SilkS")
			(hide yes)
			(effects
				(font
					(size 1.27 1.27)
				)
			)
		)
		(property "Value" ""
			(at 0 0 90)
			(layer "F.Fab")
			(effects
				(font
					(size 1.27 1.27)
				)
			)
		)
		(duplicate_pad_numbers_are_jumpers no)
		(fp_line
			(start 0.32512 -0.175006)
			(end 0.32512 0.175006)
			(stroke
				(width 0.1)
				(type default)
			)
			(layer "F.Fab")
		)
		(fp_line
			(start -0.32512 -0.175006)
			(end 0.32512 -0.175006)
			(stroke
				(width 0.1)
				(type default)
			)
			(layer "F.Fab")
		)
		(fp_line
			(start 0.32512 0.175006)
			(end -0.32512 0.175006)
			(stroke
				(width 0.1)
				(type default)
			)
			(layer "F.Fab")
		)
		(fp_line
			(start -0.32512 0.175006)
			(end -0.32512 -0.175006)
			(stroke
				(width 0.1)
				(type default)
			)
			(layer "F.Fab")
		)
		(pad "1" smd rect
			(at -0.2667 0 90)
			(size 0.3048 0.381)
			(layers "F.Cu" "F.Mask" "F.Paste")
			(net "CLK_100M_RETIMER_CPU0_P2_DP")
		)
		(pad "2" smd rect
			(at 0.2667 0 270)
			(size 0.3048 0.381)
			(layers "F.Cu" "F.Mask" "F.Paste")
			(net "GND")
		)
	)
	(footprint ""
		(layer "F.Cu")
		(at 395.269212 -321.148202 90)
		(property "Reference" "R581"
			(at 0 0 90)
			(layer "F.SilkS")
			(hide yes)
			(effects
				(font
					(size 1.27 1.27)
				)
			)
		)
		(property "Value" ""
			(at 0 0 90)
			(layer "F.Fab")
			(effects
				(font
					(size 1.27 1.27)
				)
			)
		)
		(duplicate_pad_numbers_are_jumpers no)
		(fp_line
			(start 0.7874 -0.4064)
			(end 0.7874 0.4064)
			(stroke
				(width 0.1524)
				(type default)
			)
			(layer "F.SilkS")
		)
		(fp_line
			(start -0.7874 -0.4064)
			(end 0.7874 -0.4064)
			(stroke
				(width 0.1524)
				(type default)
			)
			(layer "F.SilkS")
		)
		(fp_line
			(start 0.7874 0.4064)
			(end -0.7874 0.4064)
			(stroke
				(width 0.1524)
				(type default)
			)
			(layer "F.SilkS")
		)
		(fp_line
			(start -0.7874 0.4064)
			(end -0.7874 -0.4064)
			(stroke
				(width 0.1524)
				(type default)
			)
			(layer "F.SilkS")
		)
		(fp_line
			(start -0.12065 -0.305054)
			(end -0.12065 -0.2794)
			(stroke
				(width 0.1)
				(type default)
			)
			(layer "F.Fab")
		)
		(fp_line
			(start -0.67945 -0.305054)
			(end -0.12065 -0.305054)
			(stroke
				(width 0.1)
				(type default)
			)
			(layer "F.Fab")
		)
		(fp_line
			(start 0.67945 -0.3048)
			(end 0.67945 0.3048)
			(stroke
				(width 0.1)
				(type default)
			)
			(layer "F.Fab")
		)
		(fp_line
			(start 0.12065 -0.3048)
			(end 0.67945 -0.3048)
			(stroke
				(width 0.1)
				(type default)
			)
			(layer "F.Fab")
		)
		(fp_line
			(start 0.12065 -0.2794)
			(end 0.12065 -0.3048)
			(stroke
				(width 0.1)
				(type default)
			)
			(layer "F.Fab")
		)
		(fp_line
			(start -0.12065 -0.2794)
			(end 0.12065 -0.2794)
			(stroke
				(width 0.1)
				(type default)
			)
			(layer "F.Fab")
		)
		(fp_line
			(start 0.120396 0.2794)
			(end -0.12065 0.2794)
			(stroke
				(width 0.1)
				(type default)
			)
			(layer "F.Fab")
		)
		(fp_line
			(start -0.12065 0.2794)
			(end -0.12065 0.3048)
			(stroke
				(width 0.1)
				(type default)
			)
			(layer "F.Fab")
		)
		(fp_line
			(start 0.67945 0.3048)
			(end 0.120396 0.3048)
			(stroke
				(width 0.1)
				(type default)
			)
			(layer "F.Fab")
		)
		(fp_line
			(start 0.120396 0.3048)
			(end 0.120396 0.2794)
			(stroke
				(width 0.1)
				(type default)
			)
			(layer "F.Fab")
		)
		(fp_line
			(start -0.12065 0.3048)
			(end -0.67945 0.3048)
			(stroke
				(width 0.1)
				(type default)
			)
			(layer "F.Fab")
		)
		(fp_line
			(start -0.67945 0.3048)
			(end -0.67945 -0.305054)
			(stroke
				(width 0.1)
				(type default)
			)
			(layer "F.Fab")
		)
		(pad "1" smd circle
			(at -0.40005 0 90)
			(size 0 0)
			(layers "F.Cu" "F.Mask" "F.Paste")
			(net "RST_CPU0_RSMRST_N")
		)
		(pad "2" smd circle
			(at 0.40005 0 90)
			(size 0 0)
			(layers "F.Cu" "F.Mask" "F.Paste")
			(net "PVDD18_S5_P0")
		)
	)
)
